(kicad_pcb
	(version 20241229)
	(generator "pcbnew")
	(generator_version "9.0")
	(general
		(thickness 1.599998)
		(legacy_teardrops no)
	)
	(paper "A4")
	(title_block
		(title "Artix - Datacenter Secure Control Module (DC-SCM)")
		(date "2024-11-06")
		(rev "1.1.3")
		(comment 9 "footprints 1-3 of 544")
	)
	(layers
		(0 "F.Cu" signal)
		(4 "In1.Cu" signal)
		(6 "In2.Cu" signal)
		(8 "In3.Cu" signal)
		(10 "In4.Cu" signal)
		(12 "In5.Cu" signal)
		(14 "In6.Cu" signal)
		(2 "B.Cu" signal)
		(9 "F.Adhes" user "F.Adhesive")
		(11 "B.Adhes" user "B.Adhesive")
		(13 "F.Paste" user)
		(15 "B.Paste" user)
		(5 "F.SilkS" user "F.Silkscreen")
		(7 "B.SilkS" user "B.Silkscreen")
		(1 "F.Mask" user)
		(3 "B.Mask" user)
		(17 "Dwgs.User" user "User.Drawings")
		(19 "Cmts.User" user "User.Comments")
		(21 "Eco1.User" user "User.Eco1")
		(23 "Eco2.User" user "User.Eco2")
		(25 "Edge.Cuts" user)
		(27 "Margin" user)
		(31 "F.CrtYd" user "F.Courtyard")
		(29 "B.CrtYd" user "B.Courtyard")
		(35 "F.Fab" user)
		(33 "B.Fab" user)
	)
	(footprint "antmicro-footprints:R_0402_1005Metric"
		(layer "F.Cu")
		(at 100.574 140.075 90)
		(descr "Resistor SMD 0402")
		(tags "resistor SMD 0402")
		(property "Reference" "R60"
			(at 0.775 0.326 90)
			(layer "F.SilkS")
			(effects
				(font
					(size 0.7 0.7)
					(thickness 0.15)
				)
				(justify left bottom)
			)
		)
		(property "Value" "R_240R_0402"
			(at 0 1.4 90)
			(layer "F.Fab")
			(effects
				(font
					(size 0.7 0.7)
					(thickness 0.15)
				)
				(justify left bottom)
			)
		)
		(property "Datasheet" "https://www.bourns.com/docs/product-datasheets/cr.pdf"
			(at 0 0 90)
			(layer "F.Fab")
			(hide yes)
			(effects
				(font
					(size 1.27 1.27)
					(thickness 0.15)
				)
			)
		)
		(property "Description" "SMD Chip Resistor, 240 ohm, ± 1%, 63 mW, 0402 [1005 Metric], Thick Film, General Purpose"
			(at 0 0 90)
			(layer "F.Fab")
			(hide yes)
			(effects
				(font
					(size 1.27 1.27)
					(thickness 0.15)
				)
			)
		)
		(property "Author" "Antmicro"
			(at 240.649 39.501 0)
			(layer "F.Fab")
			(hide yes)
			(effects
				(font
					(size 1 1)
					(thickness 0.15)
				)
			)
		)
		(property "License" "Apache-2.0"
			(at 240.649 39.501 0)
			(layer "F.Fab")
			(hide yes)
			(effects
				(font
					(size 1 1)
					(thickness 0.15)
				)
			)
		)
		(property "MPN" "CR0402-FX-2400GLF"
			(at 240.649 39.501 0)
			(layer "F.Fab")
			(hide yes)
			(effects
				(font
					(size 1 1)
					(thickness 0.15)
				)
			)
		)
		(property "Manufacturer" "Bourns"
			(at 240.649 39.501 0)
			(layer "F.Fab")
			(hide yes)
			(effects
				(font
					(size 1 1)
					(thickness 0.15)
				)
			)
		)
		(property "Tolerance" "1%"
			(at 240.649 39.501 0)
			(layer "F.Fab")
			(hide yes)
			(effects
				(font
					(size 1 1)
					(thickness 0.15)
				)
			)
		)
		(property "Val" "240R"
			(at 240.649 39.501 0)
			(layer "F.Fab")
			(hide yes)
			(effects
				(font
					(size 1 1)
					(thickness 0.15)
				)
			)
		)
		(sheetname "/DDR3/")
		(sheetfile "ddr3.kicad_sch")
		(attr smd)
		(fp_rect
			(start -0.925 -0.47)
			(end 0.925 0.47)
			(stroke
				(width 0.05)
				(type default)
			)
			(fill no)
			(layer "F.CrtYd")
		)
		(fp_rect
			(start -0.5 -0.25)
			(end 0.5 0.25)
			(stroke
				(width 0.15)
				(type solid)
			)
			(fill no)
			(layer "F.Fab")
		)
		(pad "1" smd roundrect
			(at -0.48 0 90)
			(size 0.59 0.64)
			(layers "F.Cu" "F.Mask" "F.Paste")
			(roundrect_rratio 0.25)
			(net 337 "Net-(U7-ZQ)")
			(pintype "passive")
		)
		(pad "2" smd roundrect
			(at 0.48 0 90)
			(size 0.59 0.64)
			(layers "F.Cu" "F.Mask" "F.Paste")
			(roundrect_rratio 0.25)
			(net 1 "GND")
			(pintype "passive")
		)
	)
	(footprint "antmicro-footprints:C_0402_1005Metric"
		(layer "F.Cu")
		(at 98.574 154.675 90)
		(descr "Capacitor SMD 0402")
		(tags "capacitor SMD 0402")
		(property "Reference" "C62"
			(at -3.425 -8.274 90)
			(layer "F.SilkS")
			(effects
				(font
					(size 0.7 0.7)
					(thickness 0.15)
				)
				(justify left bottom)
			)
		)
		(property "Value" "C_100n_6V3_0402"
			(at 0 1.4 90)
			(layer "F.Fab")
			(effects
				(font
					(size 0.7 0.7)
					(thickness 0.15)
				)
				(justify left bottom)
			)
		)
		(property "Datasheet" "https://www.passivecomponent.com/wp-content/uploads/datasheet/WTC_MLCC_General_Purpose.pdf"
			(at 0 0 90)
			(layer "F.Fab")
			(hide yes)
			(effects
				(font
					(size 1.27 1.27)
					(thickness 0.15)
				)
			)
		)
		(property "Description" "SMT Multilayer Ceramic Capacitor, 0.1 µF, 6.3 V, 0402 [1005 Metric], ± 10%, X5R, Walsin MLCC"
			(at 0 0 90)
			(layer "F.Fab")
			(hide yes)
			(effects
				(font
					(size 1.27 1.27)
					(thickness 0.15)
				)
			)
		)
		(property "Author" "Antmicro"
			(at 253.249 56.101 0)
			(layer "F.Fab")
			(hide yes)
			(effects
				(font
					(size 1 1)
					(thickness 0.15)
				)
			)
		)
		(property "Dielectric" ""
			(at 253.249 56.101 0)
			(layer "F.Fab")
			(hide yes)
			(effects
				(font
					(size 1 1)
					(thickness 0.15)
				)
			)
		)
		(property "License" "Apache-2.0"
			(at 253.249 56.101 0)
			(layer "F.Fab")
			(hide yes)
			(effects
				(font
					(size 1 1)
					(thickness 0.15)
				)
			)
		)
		(property "MPN" "0402X104K6R3CT"
			(at 253.249 56.101 0)
			(layer "F.Fab")
			(hide yes)
			(effects
				(font
					(size 1 1)
					(thickness 0.15)
				)
			)
		)
		(property "Manufacturer" "Walsin"
			(at 253.249 56.101 0)
			(layer "F.Fab")
			(hide yes)
			(effects
				(font
					(size 1 1)
					(thickness 0.15)
				)
			)
		)
		(property "Public" "False"
			(at 253.249 56.101 0)
			(layer "F.Fab")
			(hide yes)
			(effects
				(font
					(size 1 1)
					(thickness 0.15)
				)
			)
		)
		(property "Val" "100n"
			(at 253.249 56.101 0)
			(layer "F.Fab")
			(hide yes)
			(effects
				(font
					(size 1 1)
					(thickness 0.15)
				)
			)
		)
		(property "Voltage" ""
			(at 253.249 56.101 0)
			(layer "F.Fab")
			(hide yes)
			(effects
				(font
					(size 1 1)
					(thickness 0.15)
				)
			)
		)
		(sheetname "/DDR3/")
		(sheetfile "ddr3.kicad_sch")
		(attr smd)
		(fp_rect
			(start -0.925 -0.47)
			(end 0.925 0.47)
			(stroke
				(width 0.05)
				(type default)
			)
			(fill no)
			(layer "F.CrtYd")
		)
		(fp_line
			(start 0.504 -0.25)
			(end 0.504 0.248)
			(stroke
				(width 0.15)
				(type solid)
			)
			(layer "F.Fab")
		)
		(fp_line
			(start -0.494 -0.25)
			(end 0.504 -0.25)
			(stroke
				(width 0.15)
				(type solid)
			)
			(layer "F.Fab")
		)
		(fp_line
			(start 0.504 0.248)
			(end -0.494 0.248)
			(stroke
				(width 0.15)
				(type solid)
			)
			(layer "F.Fab")
		)
		(fp_line
			(start -0.494 0.248)
			(end -0.494 -0.25)
			(stroke
				(width 0.15)
				(type solid)
			)
			(layer "F.Fab")
		)
		(pad "1" smd roundrect
			(at -0.48 0 90)
			(size 0.59 0.64)
			(layers "F.Cu" "F.Mask" "F.Paste")
			(roundrect_rratio 0.25)
			(net 1 "GND")
			(pintype "passive")
		)
		(pad "2" smd roundrect
			(at 0.48 0 90)
			(size 0.59 0.64)
			(layers "F.Cu" "F.Mask" "F.Paste")
			(roundrect_rratio 0.25)
			(net 211 "DDR3_VREF")
			(pintype "passive")
		)
	)
	(footprint "antmicro-footprints:C_0402_1005Metric"
		(layer "F.Cu")
		(at 92.174 154.675 90)
		(descr "Capacitor SMD 0402")
		(tags "capacitor SMD 0402")
		(property "Reference" "C48"
			(at -3.425 -7.574 90)
			(layer "F.SilkS")
			(effects
				(font
					(size 0.7 0.7)
					(thickness 0.15)
				)
				(justify left bottom)
			)
		)
		(property "Value" "C_4u7_0402"
			(at 0 1.4 90)
			(layer "F.Fab")
			(effects
				(font
					(size 0.7 0.7)
					(thickness 0.15)
				)
				(justify left bottom)
			)
		)
		(property "Datasheet" "https://www.murata.com/products/productdetail?partno=GRM155R61A475MEAA%23"
			(at 0 0 90)
			(layer "F.Fab")
			(hide yes)
			(effects
				(font
					(size 1.27 1.27)
					(thickness 0.15)
				)
			)
		)
		(property "Description" "SMD Multilayer Ceramic Capacitor, 4.7 µF, 10 V, 0402 [1005 Metric], ± 20%, X5R, GRM Series"
			(at 0 0 90)
			(layer "F.Fab")
			(hide yes)
			(effects
				(font
					(size 1.27 1.27)
					(thickness 0.15)
				)
			)
		)
		(property "Author" "Antmicro"
			(at 246.849 62.501 0)
			(layer "F.Fab")
			(hide yes)
			(effects
				(font
					(size 1 1)
					(thickness 0.15)
				)
			)
		)
		(property "Dielectric" ""
			(at 246.849 62.501 0)
			(layer "F.Fab")
			(hide yes)
			(effects
				(font
					(size 1 1)
					(thickness 0.15)
				)
			)
		)
		(property "License" "Apache-2.0"
			(at 246.849 62.501 0)
			(layer "F.Fab")
			(hide yes)
			(effects
				(font
					(size 1 1)
					(thickness 0.15)
				)
			)
		)
		(property "MPN" "GRM155R61A475MEAAD"
			(at 246.849 62.501 0)
			(layer "F.Fab")
			(hide yes)
			(effects
				(font
					(size 1 1)
					(thickness 0.15)
				)
			)
		)
		(property "Manufacturer" "Murata"
			(at 246.849 62.501 0)
			(layer "F.Fab")
			(hide yes)
			(effects
				(font
					(size 1 1)
					(thickness 0.15)
				)
			)
		)
		(property "Val" "4u7"
			(at 246.849 62.501 0)
			(layer "F.Fab")
			(hide yes)
			(effects
				(font
					(size 1 1)
					(thickness 0.15)
				)
			)
		)
		(property "Voltage" ""
			(at 246.849 62.501 0)
			(layer "F.Fab")
			(hide yes)
			(effects
				(font
					(size 1 1)
					(thickness 0.15)
				)
			)
		)
		(sheetname "/DDR3/")
		(sheetfile "ddr3.kicad_sch")
		(attr smd)
		(fp_rect
			(start -0.925 -0.47)
			(end 0.925 0.47)
			(stroke
				(width 0.05)
				(type default)
			)
			(fill no)
			(layer "F.CrtYd")
		)
		(fp_line
			(start 0.504 -0.25)
			(end 0.504 0.248)
			(stroke
				(width 0.15)
				(type solid)
			)
			(layer "F.Fab")
		)
		(fp_line
			(start -0.494 -0.25)
			(end 0.504 -0.25)
			(stroke
				(width 0.15)
				(type solid)
			)
			(layer "F.Fab")
		)
		(fp_line
			(start 0.504 0.248)
			(end -0.494 0.248)
			(stroke
				(width 0.15)
				(type solid)
			)
			(layer "F.Fab")
		)
		(fp_line
			(start -0.494 0.248)
			(end -0.494 -0.25)
			(stroke
				(width 0.15)
				(type solid)
			)
			(layer "F.Fab")
		)
		(pad "1" smd roundrect
			(at -0.48 0 90)
			(size 0.59 0.64)
			(layers "F.Cu" "F.Mask" "F.Paste")
			(roundrect_rratio 0.25)
			(net 1 "GND")
			(pintype "passive")
		)
		(pad "2" smd roundrect
			(at 0.48 0 90)
			(size 0.59 0.64)
			(layers "F.Cu" "F.Mask" "F.Paste")
			(roundrect_rratio 0.25)
			(net 3 "VCC1V35")
			(pintype "passive")
		)
	)
)
